(kicad_pcb
	(version 20260206)
	(generator "pcbnew")
	(generator_version "10.0")
	(general
		(thickness 1.6)
		(legacy_teardrops no)
	)
	(paper "A4")
	(title_block
		(title "04192023_DAF0TMB3IC0_F0TG_MB_C_brd_V02_OCP.brd")
		(comment 1 "Grand Teton / footprints 913-919 of 8354")
	)
	(layers
		(0 "F.Cu" signal "TOP")
		(4 "In1.Cu" signal "GND")
		(6 "In2.Cu" signal "IN1")
		(8 "In3.Cu" signal "GND1")
		(10 "In4.Cu" signal "IN2")
		(12 "In5.Cu" signal "GND2")
		(14 "In6.Cu" signal "IN3")
		(16 "In7.Cu" signal "GND3")
		(18 "In8.Cu" signal "VCC")
		(20 "In9.Cu" signal "VCC1")
		(22 "In10.Cu" signal "GND4")
		(24 "In11.Cu" signal "IN4")
		(26 "In12.Cu" signal "GND5")
		(28 "In13.Cu" signal "IN5")
		(30 "In14.Cu" signal "GND6")
		(32 "In15.Cu" signal "IN6")
		(34 "In16.Cu" signal "GND7")
		(2 "B.Cu" signal "BOTTOM")
		(9 "F.Adhes" user "F.Adhesive")
		(11 "B.Adhes" user "B.Adhesive")
		(13 "F.Paste" user "Package Geometry/Pastemask Top")
		(15 "B.Paste" user "Package Geometry/Pastemask Bottom")
		(5 "F.SilkS" user "Ref Des/Silkscreen Top")
		(7 "B.SilkS" user "Ref Des/Silkscreen Bottom")
		(1 "F.Mask" user "Board Geometry/Soldermask Top")
		(3 "B.Mask" user "Board Geometry/Soldermask Bottom")
		(17 "Dwgs.User" user "User.Drawings")
		(19 "Cmts.User" user "User.Comments")
		(21 "Eco1.User" user "User.Eco1")
		(23 "Eco2.User" user "User.Eco2")
		(25 "Edge.Cuts" user "Board Geometry/Outline")
		(27 "Margin" user)
		(31 "F.CrtYd" user "Package Geometry/Place Bound Top")
		(29 "B.CrtYd" user "Package Geometry/Place Bound Bottom")
		(35 "F.Fab" user "Ref Des/Assembly Top")
		(33 "B.Fab" user "Ref Des/Assembly Bottom")
	)
	(footprint ""
		(layer "F.Cu")
		(at 110.089696 -373.03583 -90)
		(property "Reference" "C1543"
			(at 0 0 270)
			(layer "F.SilkS")
			(hide yes)
			(effects
				(font
					(size 1.27 1.27)
				)
			)
		)
		(property "Value" ""
			(at 0 0 270)
			(layer "F.Fab")
			(effects
				(font
					(size 1.27 1.27)
				)
			)
		)
		(duplicate_pad_numbers_are_jumpers no)
		(fp_line
			(start -0.299974 0.150114)
			(end -0.299974 -0.150114)
			(stroke
				(width 0.1)
				(type default)
			)
			(layer "F.Fab")
		)
		(fp_line
			(start 0.299974 0.150114)
			(end -0.299974 0.150114)
			(stroke
				(width 0.1)
				(type default)
			)
			(layer "F.Fab")
		)
		(fp_line
			(start -0.299974 -0.150114)
			(end 0.299974 -0.150114)
			(stroke
				(width 0.1)
				(type default)
			)
			(layer "F.Fab")
		)
		(fp_line
			(start 0.299974 -0.150114)
			(end 0.299974 0.150114)
			(stroke
				(width 0.1)
				(type default)
			)
			(layer "F.Fab")
		)
		(pad "1" smd rect
			(at -0.2667 0 270)
			(size 0.3048 0.381)
			(layers "F.Cu" "F.Mask" "F.Paste")
			(net "P5E_CPU1_P3_TX_C_DP<2>")
		)
		(pad "2" smd rect
			(at 0.2667 0 270)
			(size 0.3048 0.381)
			(layers "F.Cu" "F.Mask" "F.Paste")
			(net "P5E_CPU1_P3_TX_DP<2>")
		)
	)
	(footprint ""
		(layer "F.Cu")
		(at 26.226516 -40.180514)
		(property "Reference" "C1109"
			(at 0 0 0)
			(layer "F.SilkS")
			(hide yes)
			(effects
				(font
					(size 1.27 1.27)
				)
			)
		)
		(property "Value" ""
			(at 0 0 0)
			(layer "F.Fab")
			(effects
				(font
					(size 1.27 1.27)
				)
			)
		)
		(duplicate_pad_numbers_are_jumpers no)
		(fp_line
			(start -0.7874 -0.4064)
			(end 0.7874 -0.4064)
			(stroke
				(width 0.1524)
				(type default)
			)
			(layer "F.SilkS")
		)
		(fp_line
			(start -0.7874 0.4064)
			(end -0.7874 -0.4064)
			(stroke
				(width 0.1524)
				(type default)
			)
			(layer "F.SilkS")
		)
		(fp_line
			(start 0.7874 -0.4064)
			(end 0.7874 0.4064)
			(stroke
				(width 0.1524)
				(type default)
			)
			(layer "F.SilkS")
		)
		(fp_line
			(start 0.7874 0.4064)
			(end -0.7874 0.4064)
			(stroke
				(width 0.1524)
				(type default)
			)
			(layer "F.SilkS")
		)
		(fp_line
			(start -0.67945 -0.305054)
			(end -0.12065 -0.305054)
			(stroke
				(width 0.1)
				(type default)
			)
			(layer "F.Fab")
		)
		(fp_line
			(start -0.67945 0.3048)
			(end -0.67945 -0.305054)
			(stroke
				(width 0.1)
				(type default)
			)
			(layer "F.Fab")
		)
		(fp_line
			(start -0.12065 -0.305054)
			(end -0.12065 -0.2794)
			(stroke
				(width 0.1)
				(type default)
			)
			(layer "F.Fab")
		)
		(fp_line
			(start -0.12065 -0.2794)
			(end 0.12065 -0.2794)
			(stroke
				(width 0.1)
				(type default)
			)
			(layer "F.Fab")
		)
		(fp_line
			(start -0.12065 0.2794)
			(end -0.12065 0.3048)
			(stroke
				(width 0.1)
				(type default)
			)
			(layer "F.Fab")
		)
		(fp_line
			(start -0.12065 0.3048)
			(end -0.67945 0.3048)
			(stroke
				(width 0.1)
				(type default)
			)
			(layer "F.Fab")
		)
		(fp_line
			(start 0.120396 0.2794)
			(end -0.12065 0.2794)
			(stroke
				(width 0.1)
				(type default)
			)
			(layer "F.Fab")
		)
		(fp_line
			(start 0.120396 0.3048)
			(end 0.120396 0.2794)
			(stroke
				(width 0.1)
				(type default)
			)
			(layer "F.Fab")
		)
		(fp_line
			(start 0.12065 -0.3048)
			(end 0.67945 -0.3048)
			(stroke
				(width 0.1)
				(type default)
			)
			(layer "F.Fab")
		)
		(fp_line
			(start 0.12065 -0.2794)
			(end 0.12065 -0.3048)
			(stroke
				(width 0.1)
				(type default)
			)
			(layer "F.Fab")
		)
		(fp_line
			(start 0.67945 -0.3048)
			(end 0.67945 0.3048)
			(stroke
				(width 0.1)
				(type default)
			)
			(layer "F.Fab")
		)
		(fp_line
			(start 0.67945 0.3048)
			(end 0.120396 0.3048)
			(stroke
				(width 0.1)
				(type default)
			)
			(layer "F.Fab")
		)
		(pad "1" smd circle
			(at -0.40005 0)
			(size 0 0)
			(layers "F.Cu" "F.Mask" "F.Paste")
			(net "P12V_OCP_V3_2")
		)
		(pad "2" smd circle
			(at 0.40005 0)
			(size 0 0)
			(layers "F.Cu" "F.Mask" "F.Paste")
			(net "GND")
		)
	)
	(footprint ""
		(layer "F.Cu")
		(at 120.327928 -165.109906 90)
		(property "Reference" "PC324_2"
			(at 0 0 90)
			(layer "F.SilkS")
			(hide yes)
			(effects
				(font
					(size 1.27 1.27)
				)
			)
		)
		(property "Value" ""
			(at 0 0 90)
			(layer "F.Fab")
			(effects
				(font
					(size 1.27 1.27)
				)
			)
		)
		(duplicate_pad_numbers_are_jumpers no)
		(fp_line
			(start 0.7874 -0.4064)
			(end 0.7874 0.4064)
			(stroke
				(width 0.1524)
				(type default)
			)
			(layer "F.SilkS")
		)
		(fp_line
			(start -0.7874 -0.4064)
			(end 0.7874 -0.4064)
			(stroke
				(width 0.1524)
				(type default)
			)
			(layer "F.SilkS")
		)
		(fp_line
			(start 0.7874 0.4064)
			(end -0.7874 0.4064)
			(stroke
				(width 0.1524)
				(type default)
			)
			(layer "F.SilkS")
		)
		(fp_line
			(start -0.7874 0.4064)
			(end -0.7874 -0.4064)
			(stroke
				(width 0.1524)
				(type default)
			)
			(layer "F.SilkS")
		)
		(fp_line
			(start -0.12065 -0.305054)
			(end -0.12065 -0.2794)
			(stroke
				(width 0.1)
				(type default)
			)
			(layer "F.Fab")
		)
		(fp_line
			(start -0.67945 -0.305054)
			(end -0.12065 -0.305054)
			(stroke
				(width 0.1)
				(type default)
			)
			(layer "F.Fab")
		)
		(fp_line
			(start 0.67945 -0.3048)
			(end 0.67945 0.3048)
			(stroke
				(width 0.1)
				(type default)
			)
			(layer "F.Fab")
		)
		(fp_line
			(start 0.12065 -0.3048)
			(end 0.67945 -0.3048)
			(stroke
				(width 0.1)
				(type default)
			)
			(layer "F.Fab")
		)
		(fp_line
			(start 0.12065 -0.2794)
			(end 0.12065 -0.3048)
			(stroke
				(width 0.1)
				(type default)
			)
			(layer "F.Fab")
		)
		(fp_line
			(start -0.12065 -0.2794)
			(end 0.12065 -0.2794)
			(stroke
				(width 0.1)
				(type default)
			)
			(layer "F.Fab")
		)
		(fp_line
			(start 0.120396 0.2794)
			(end -0.12065 0.2794)
			(stroke
				(width 0.1)
				(type default)
			)
			(layer "F.Fab")
		)
		(fp_line
			(start -0.12065 0.2794)
			(end -0.12065 0.3048)
			(stroke
				(width 0.1)
				(type default)
			)
			(layer "F.Fab")
		)
		(fp_line
			(start 0.67945 0.3048)
			(end 0.120396 0.3048)
			(stroke
				(width 0.1)
				(type default)
			)
			(layer "F.Fab")
		)
		(fp_line
			(start 0.120396 0.3048)
			(end 0.120396 0.2794)
			(stroke
				(width 0.1)
				(type default)
			)
			(layer "F.Fab")
		)
		(fp_line
			(start -0.12065 0.3048)
			(end -0.67945 0.3048)
			(stroke
				(width 0.1)
				(type default)
			)
			(layer "F.Fab")
		)
		(fp_line
			(start -0.67945 0.3048)
			(end -0.67945 -0.305054)
			(stroke
				(width 0.1)
				(type default)
			)
			(layer "F.Fab")
		)
		(pad "1" smd circle
			(at -0.40005 0 90)
			(size 0 0)
			(layers "F.Cu" "F.Mask" "F.Paste")
			(net "SW_P12V_AUX_PVDDCR_SOC_P1_FLT")
		)
		(pad "2" smd circle
			(at 0.40005 0 90)
			(size 0 0)
			(layers "F.Cu" "F.Mask" "F.Paste")
			(net "GND")
		)
	)
	(footprint ""
		(layer "F.Cu")
		(at 421.798496 -357.688134 -90)
		(property "Reference" "PR35"
			(at 0 0 270)
			(layer "F.SilkS")
			(hide yes)
			(effects
				(font
					(size 1.27 1.27)
				)
			)
		)
		(property "Value" ""
			(at 0 0 270)
			(layer "F.Fab")
			(effects
				(font
					(size 1.27 1.27)
				)
			)
		)
		(duplicate_pad_numbers_are_jumpers no)
		(fp_line
			(start -0.7874 0.4064)
			(end -0.7874 -0.4064)
			(stroke
				(width 0.1524)
				(type default)
			)
			(layer "F.SilkS")
		)
		(fp_line
			(start 0.7874 0.4064)
			(end -0.7874 0.4064)
			(stroke
				(width 0.1524)
				(type default)
			)
			(layer "F.SilkS")
		)
		(fp_line
			(start -0.7874 -0.4064)
			(end 0.7874 -0.4064)
			(stroke
				(width 0.1524)
				(type default)
			)
			(layer "F.SilkS")
		)
		(fp_line
			(start 0.7874 -0.4064)
			(end 0.7874 0.4064)
			(stroke
				(width 0.1524)
				(type default)
			)
			(layer "F.SilkS")
		)
		(fp_line
			(start -0.67945 0.3048)
			(end -0.67945 -0.305054)
			(stroke
				(width 0.1)
				(type default)
			)
			(layer "F.Fab")
		)
		(fp_line
			(start -0.12065 0.3048)
			(end -0.67945 0.3048)
			(stroke
				(width 0.1)
				(type default)
			)
			(layer "F.Fab")
		)
		(fp_line
			(start 0.120396 0.3048)
			(end 0.120396 0.2794)
			(stroke
				(width 0.1)
				(type default)
			)
			(layer "F.Fab")
		)
		(fp_line
			(start 0.67945 0.3048)
			(end 0.120396 0.3048)
			(stroke
				(width 0.1)
				(type default)
			)
			(layer "F.Fab")
		)
		(fp_line
			(start -0.12065 0.2794)
			(end -0.12065 0.3048)
			(stroke
				(width 0.1)
				(type default)
			)
			(layer "F.Fab")
		)
		(fp_line
			(start 0.120396 0.2794)
			(end -0.12065 0.2794)
			(stroke
				(width 0.1)
				(type default)
			)
			(layer "F.Fab")
		)
		(fp_line
			(start -0.12065 -0.2794)
			(end 0.12065 -0.2794)
			(stroke
				(width 0.1)
				(type default)
			)
			(layer "F.Fab")
		)
		(fp_line
			(start 0.12065 -0.2794)
			(end 0.12065 -0.3048)
			(stroke
				(width 0.1)
				(type default)
			)
			(layer "F.Fab")
		)
		(fp_line
			(start 0.12065 -0.3048)
			(end 0.67945 -0.3048)
			(stroke
				(width 0.1)
				(type default)
			)
			(layer "F.Fab")
		)
		(fp_line
			(start 0.67945 -0.3048)
			(end 0.67945 0.3048)
			(stroke
				(width 0.1)
				(type default)
			)
			(layer "F.Fab")
		)
		(fp_line
			(start -0.67945 -0.305054)
			(end -0.12065 -0.305054)
			(stroke
				(width 0.1)
				(type default)
			)
			(layer "F.Fab")
		)
		(fp_line
			(start -0.12065 -0.305054)
			(end -0.12065 -0.2794)
			(stroke
				(width 0.1)
				(type default)
			)
			(layer "F.Fab")
		)
		(pad "1" smd circle
			(at -0.40005 0 270)
			(size 0 0)
			(layers "F.Cu" "F.Mask" "F.Paste")
			(net "NC_PVDD11_S3_P0_IMON6")
		)
		(pad "2" smd circle
			(at 0.40005 0 270)
			(size 0 0)
			(layers "F.Cu" "F.Mask" "F.Paste")
			(net "GND")
		)
	)
	(footprint ""
		(layer "F.Cu")
		(at 455.01306 -39.835836 180)
		(property "Reference" "R3784"
			(at 0 0 180)
			(layer "F.SilkS")
			(hide yes)
			(effects
				(font
					(size 1.27 1.27)
				)
			)
		)
		(property "Value" ""
			(at 0 0 180)
			(layer "F.Fab")
			(effects
				(font
					(size 1.27 1.27)
				)
			)
		)
		(duplicate_pad_numbers_are_jumpers no)
		(fp_line
			(start 0.7874 0.4064)
			(end -0.7874 0.4064)
			(stroke
				(width 0.1524)
				(type default)
			)
			(layer "F.SilkS")
		)
		(fp_line
			(start 0.7874 -0.4064)
			(end 0.7874 0.4064)
			(stroke
				(width 0.1524)
				(type default)
			)
			(layer "F.SilkS")
		)
		(fp_line
			(start -0.7874 0.4064)
			(end -0.7874 -0.4064)
			(stroke
				(width 0.1524)
				(type default)
			)
			(layer "F.SilkS")
		)
		(fp_line
			(start -0.7874 -0.4064)
			(end 0.7874 -0.4064)
			(stroke
				(width 0.1524)
				(type default)
			)
			(layer "F.SilkS")
		)
		(fp_line
			(start 0.67945 0.3048)
			(end 0.120396 0.3048)
			(stroke
				(width 0.1)
				(type default)
			)
			(layer "F.Fab")
		)
		(fp_line
			(start 0.67945 -0.3048)
			(end 0.67945 0.3048)
			(stroke
				(width 0.1)
				(type default)
			)
			(layer "F.Fab")
		)
		(fp_line
			(start 0.12065 -0.2794)
			(end 0.12065 -0.3048)
			(stroke
				(width 0.1)
				(type default)
			)
			(layer "F.Fab")
		)
		(fp_line
			(start 0.12065 -0.3048)
			(end 0.67945 -0.3048)
			(stroke
				(width 0.1)
				(type default)
			)
			(layer "F.Fab")
		)
		(fp_line
			(start 0.120396 0.3048)
			(end 0.120396 0.2794)
			(stroke
				(width 0.1)
				(type default)
			)
			(layer "F.Fab")
		)
		(fp_line
			(start 0.120396 0.2794)
			(end -0.12065 0.2794)
			(stroke
				(width 0.1)
				(type default)
			)
			(layer "F.Fab")
		)
		(fp_line
			(start -0.12065 0.3048)
			(end -0.67945 0.3048)
			(stroke
				(width 0.1)
				(type default)
			)
			(layer "F.Fab")
		)
		(fp_line
			(start -0.12065 0.2794)
			(end -0.12065 0.3048)
			(stroke
				(width 0.1)
				(type default)
			)
			(layer "F.Fab")
		)
		(fp_line
			(start -0.12065 -0.2794)
			(end 0.12065 -0.2794)
			(stroke
				(width 0.1)
				(type default)
			)
			(layer "F.Fab")
		)
		(fp_line
			(start -0.12065 -0.305054)
			(end -0.12065 -0.2794)
			(stroke
				(width 0.1)
				(type default)
			)
			(layer "F.Fab")
		)
		(fp_line
			(start -0.67945 0.3048)
			(end -0.67945 -0.305054)
			(stroke
				(width 0.1)
				(type default)
			)
			(layer "F.Fab")
		)
		(fp_line
			(start -0.67945 -0.305054)
			(end -0.12065 -0.305054)
			(stroke
				(width 0.1)
				(type default)
			)
			(layer "F.Fab")
		)
		(pad "1" smd circle
			(at -0.40005 0 180)
			(size 0 0)
			(layers "F.Cu" "F.Mask" "F.Paste")
			(net "P12V_OCP_UV_1_R")
		)
		(pad "2" smd circle
			(at 0.40005 0 180)
			(size 0 0)
			(layers "F.Cu" "F.Mask" "F.Paste")
			(net "P12V_OCP_UV_1")
		)
	)
	(footprint ""
		(layer "F.Cu")
		(at 449.692268 -72.373236 180)
		(property "Reference" "PC1867"
			(at 4.842256 -2.972562 0)
			(unlocked yes)
			(layer "F.SilkS")
			(effects
				(font
					(size 0.7874 0.5842)
					(thickness 0.1524)
				)
				(justify left)
			)
		)
		(property "Value" ""
			(at 0 0 180)
			(layer "F.Fab")
			(effects
				(font
					(size 1.27 1.27)
				)
			)
		)
		(duplicate_pad_numbers_are_jumpers no)
		(fp_line
			(start -3.400044 1.249934)
			(end 3.400044 1.249934)
			(stroke
				(width 0.1524)
				(type default)
			)
			(layer "F.SilkS")
		)
		(fp_circle
			(center 0 1.249934)
			(end -3.400044 1.249934)
			(stroke
				(width 0.1524)
				(type default)
			)
			(fill no)
			(layer "F.SilkS")
		)
		(fp_poly
			(pts
				(arc
					(start 3.400044 1.249934)
					(mid 0 4.649978)
					(end -3.400044 1.249934)
				)
			)
			(stroke
				(width 0)
				(type default)
			)
			(fill yes)
			(layer "F.SilkS")
		)
		(fp_circle
			(center 0 1.249934)
			(end -3.400044 1.249934)
			(stroke
				(width 0.1)
				(type default)
			)
			(fill no)
			(layer "F.Fab")
		)
		(pad "1" thru_hole rect
			(at 0 0 180)
			(size 1.524 1.524)
			(drill 1.016)
			(layers "*.Cu" "*.Mask")
			(remove_unused_layers no)
			(net "P3V3_AUX")
			(clearance 0)
			(padstack
				(mode front_inner_back)
				(layer "Inner"
					(shape circle)
					(size 1.524 1.524)
					(clearance 0)
				)
				(layer "B.Cu"
					(shape rect)
					(size 1.524 1.524)
					(clearance 0)
				)
			)
		)
		(pad "2" thru_hole circle
			(at 0 2.500122 180)
			(size 1.524 1.524)
			(drill 1.016)
			(layers "*.Cu" "*.Mask")
			(remove_unused_layers no)
			(net "GND")
			(clearance 0)
		)
	)
	(footprint ""
		(layer "F.Cu")
		(at 331.633068 -136.473946)
		(property "Reference" "R8465"
			(at 0 0 0)
			(layer "F.SilkS")
			(hide yes)
			(effects
				(font
					(size 1.27 1.27)
				)
			)
		)
		(property "Value" ""
			(at 0 0 0)
			(layer "F.Fab")
			(effects
				(font
					(size 1.27 1.27)
				)
			)
		)
		(duplicate_pad_numbers_are_jumpers no)
		(fp_line
			(start -0.7874 -0.4064)
			(end 0.7874 -0.4064)
			(stroke
				(width 0.1524)
				(type default)
			)
			(layer "F.SilkS")
		)
		(fp_line
			(start -0.7874 0.4064)
			(end -0.7874 -0.4064)
			(stroke
				(width 0.1524)
				(type default)
			)
			(layer "F.SilkS")
		)
		(fp_line
			(start 0.7874 -0.4064)
			(end 0.7874 0.4064)
			(stroke
				(width 0.1524)
				(type default)
			)
			(layer "F.SilkS")
		)
		(fp_line
			(start 0.7874 0.4064)
			(end -0.7874 0.4064)
			(stroke
				(width 0.1524)
				(type default)
			)
			(layer "F.SilkS")
		)
		(fp_line
			(start -0.67945 -0.305054)
			(end -0.12065 -0.305054)
			(stroke
				(width 0.1)
				(type default)
			)
			(layer "F.Fab")
		)
		(fp_line
			(start -0.67945 0.3048)
			(end -0.67945 -0.305054)
			(stroke
				(width 0.1)
				(type default)
			)
			(layer "F.Fab")
		)
		(fp_line
			(start -0.12065 -0.305054)
			(end -0.12065 -0.2794)
			(stroke
				(width 0.1)
				(type default)
			)
			(layer "F.Fab")
		)
		(fp_line
			(start -0.12065 -0.2794)
			(end 0.12065 -0.2794)
			(stroke
				(width 0.1)
				(type default)
			)
			(layer "F.Fab")
		)
		(fp_line
			(start -0.12065 0.2794)
			(end -0.12065 0.3048)
			(stroke
				(width 0.1)
				(type default)
			)
			(layer "F.Fab")
		)
		(fp_line
			(start -0.12065 0.3048)
			(end -0.67945 0.3048)
			(stroke
				(width 0.1)
				(type default)
			)
			(layer "F.Fab")
		)
		(fp_line
			(start 0.120396 0.2794)
			(end -0.12065 0.2794)
			(stroke
				(width 0.1)
				(type default)
			)
			(layer "F.Fab")
		)
		(fp_line
			(start 0.120396 0.3048)
			(end 0.120396 0.2794)
			(stroke
				(width 0.1)
				(type default)
			)
			(layer "F.Fab")
		)
		(fp_line
			(start 0.12065 -0.3048)
			(end 0.67945 -0.3048)
			(stroke
				(width 0.1)
				(type default)
			)
			(layer "F.Fab")
		)
		(fp_line
			(start 0.12065 -0.2794)
			(end 0.12065 -0.3048)
			(stroke
				(width 0.1)
				(type default)
			)
			(layer "F.Fab")
		)
		(fp_line
			(start 0.67945 -0.3048)
			(end 0.67945 0.3048)
			(stroke
				(width 0.1)
				(type default)
			)
			(layer "F.Fab")
		)
		(fp_line
			(start 0.67945 0.3048)
			(end 0.120396 0.3048)
			(stroke
				(width 0.1)
				(type default)
			)
			(layer "F.Fab")
		)
		(pad "1" smd circle
			(at -0.40005 0)
			(size 0 0)
			(layers "F.Cu" "F.Mask" "F.Paste")
			(net "P3V3_AUX")
		)
		(pad "2" smd circle
			(at 0.40005 0)
			(size 0 0)
			(layers "F.Cu" "F.Mask" "F.Paste")
			(net "PWRGD_PVDD18_S5_P0")
		)
	)
)
